# SCM (Grand Teton) — schematic netlist excerpt (pin names and nets, part order shuffled) for the footprints in the layout excerpt that follows; sources: Cadence DE-HDL packaged netlist, KiCad conversion of 12092022_DA0F0TMDCD0_F0T_Management_Board_D_brd_V3_OCP.brd

J28  PICOPROBE_BXA  DELTA-L 4.0 EMPTY  pkg TRIANG_LAUNCH_3PXB  page 58
  \1_p\  = 85_10INCH_IN1_DN
  \2_n\  = 85_10INCH_IN1_DP
  \3_g\  = GND_P1

(kicad_pcb
	(version 20260206)
	(generator "pcbnew")
	(generator_version "10.0")
	(general
		(thickness 1.6)
		(legacy_teardrops no)
	)
	(paper "A4")
	(title_block
		(title "12092022_DA0F0TMDCD0_F0T_Management_Board_D_brd_V3_OCP.brd")
		(comment 1 "Grand Teton / footprints 1219-1219 of 1440")
	)
	(layers
		(0 "F.Cu" signal "TOP")
		(4 "In1.Cu" signal "GND")
		(6 "In2.Cu" signal "IN1")
		(8 "In3.Cu" signal "GND1")
		(10 "In4.Cu" signal "IN2")
		(12 "In5.Cu" signal "VCC")
		(14 "In6.Cu" signal "VCC1")
		(16 "In7.Cu" signal "IN3")
		(18 "In8.Cu" signal "GND2")
		(20 "In9.Cu" signal "IN4")
		(22 "In10.Cu" signal "GND3")
		(2 "B.Cu" signal "BOTTOM")
		(9 "F.Adhes" user "F.Adhesive")
		(11 "B.Adhes" user "B.Adhesive")
		(13 "F.Paste" user "Package Geometry/Pastemask Top")
		(15 "B.Paste" user "Package Geometry/Pastemask Bottom")
		(5 "F.SilkS" user "Ref Des/Silkscreen Top")
		(7 "B.SilkS" user "Ref Des/Silkscreen Bottom")
		(1 "F.Mask" user "Board Geometry/Soldermask Top")
		(3 "B.Mask" user "Board Geometry/Soldermask Bottom")
		(17 "Dwgs.User" user "User.Drawings")
		(19 "Cmts.User" user "User.Comments")
		(21 "Eco1.User" user "User.Eco1")
		(23 "Eco2.User" user "User.Eco2")
		(25 "Edge.Cuts" user "Board Geometry/Outline")
		(27 "Margin" user)
		(31 "F.CrtYd" user "Package Geometry/Place Bound Top")
		(29 "B.CrtYd" user "Package Geometry/Place Bound Bottom")
		(35 "F.Fab" user "Ref Des/Assembly Top")
		(33 "B.Fab" user "Ref Des/Assembly Bottom")
	)
	(footprint ""
		(layer "B.Cu")
		(at 101.29012 29.261562 90)
		(property "Reference" "J28"
			(at -1.218438 -2.89179 270)
			(unlocked yes)
			(layer "B.SilkS")
			(effects
				(font
					(size 0.7874 0.5842)
					(thickness 0.1524)
				)
				(justify left mirror)
			)
		)
		(property "Value" ""
			(at 0 0 90)
			(layer "B.Fab")
			(effects
				(font
					(size 1.27 1.27)
				)
				(justify mirror)
			)
		)
		(duplicate_pad_numbers_are_jumpers no)
		(fp_line
			(start 1.2192 -2.1082)
			(end -1.2192 -2.1082)
			(stroke
				(width 0.1524)
				(type default)
			)
			(layer "B.SilkS")
		)
		(fp_line
			(start -1.2192 -2.1082)
			(end -1.2192 -0.831596)
			(stroke
				(width 0.1524)
				(type default)
			)
			(layer "B.SilkS")
		)
		(fp_line
			(start -1.2192 0.909574)
			(end -1.2192 2.1082)
			(stroke
				(width 0.1524)
				(type default)
			)
			(layer "B.SilkS")
		)
		(fp_line
			(start 1.2192 2.1082)
			(end 1.2192 -2.1082)
			(stroke
				(width 0.1524)
				(type default)
			)
			(layer "B.SilkS")
		)
		(fp_line
			(start -1.2192 2.1082)
			(end 1.2192 2.1082)
			(stroke
				(width 0.1524)
				(type default)
			)
			(layer "B.SilkS")
		)
		(pad "" np_thru_hole circle
			(at -3.4671 -1.27)
			(size 1.0414 1.0414)
			(drill 1.0414)
			(layers "*.Cu" "*.Mask")
			(clearance 0.381)
			(thermal_gap 0.381)
		)
		(pad "" np_thru_hole circle
			(at -3.4671 1.27)
			(size 1.0414 1.0414)
			(drill 1.0414)
			(layers "*.Cu" "*.Mask")
			(clearance 0.381)
			(thermal_gap 0.381)
		)
		(pad "" np_thru_hole circle
			(at 2.8829 -1.27)
			(size 1.0414 1.0414)
			(drill 1.0414)
			(layers "*.Cu" "*.Mask")
			(clearance 0.381)
			(thermal_gap 0.381)
		)
		(pad "" np_thru_hole circle
			(at 2.8829 1.27)
			(size 1.0414 1.0414)
			(drill 1.0414)
			(layers "*.Cu" "*.Mask")
			(clearance 0.381)
			(thermal_gap 0.381)
		)
		(pad "1" smd rect
			(at -0.8255 -0.249936)
			(size 0.3048 0.508)
			(layers "B.Cu" "B.Mask" "B.Paste")
			(net "85_10INCH_IN1_DN")
		)
		(pad "2" smd rect
			(at -0.8255 0.249936)
			(size 0.3048 0.508)
			(layers "B.Cu" "B.Mask" "B.Paste")
			(net "85_10INCH_IN1_DP")
		)
		(pad "3" smd circle
			(at 0 0 270)
			(size 0 0)
			(layers "B.Cu" "B.Mask" "B.Paste")
			(net "GND_P1")
		)
		(zone
			(layers "F.Cu" "B.Cu" "In1.Cu" "In2.Cu" "In3.Cu" "In4.Cu" "In5.Cu" "In6.Cu"
				"In7.Cu" "In8.Cu" "In9.Cu" "In10.Cu"
			)
			(hatch none 0.5)
			(connect_pads
				(clearance 0)
			)
			(min_thickness 0.25)
			(keepout
				(tracks not_allowed)
				(vias allowed)
				(pads allowed)
				(copperpour not_allowed)
				(footprints allowed)
			)
			(placement
				(enabled no)
				(sheetname "")
			)
			(fill
				(thermal_gap 0.5)
				(thermal_bridge_width 0.5)
				(island_removal_mode 0)
			)
			(polygon
				(pts
					(arc
						(start 100.94722 26.378662)
						(mid 99.09302 26.378662)
						(end 100.94722 26.378662)
					)
				)
			)
		)
		(zone
			(layers "F.Cu" "B.Cu" "In1.Cu" "In2.Cu" "In3.Cu" "In4.Cu" "In5.Cu" "In6.Cu"
				"In7.Cu" "In8.Cu" "In9.Cu" "In10.Cu"
			)
			(hatch none 0.5)
			(connect_pads
				(clearance 0)
			)
			(min_thickness 0.25)
			(keepout
				(tracks not_allowed)
				(vias allowed)
				(pads allowed)
				(copperpour not_allowed)
				(footprints allowed)
			)
			(placement
				(enabled no)
				(sheetname "")
			)
			(fill
				(thermal_gap 0.5)
				(thermal_bridge_width 0.5)
				(island_removal_mode 0)
			)
			(polygon
				(pts
					(arc
						(start 100.94722 32.728662)
						(mid 99.09302 32.728662)
						(end 100.94722 32.728662)
					)
				)
			)
		)
		(zone
			(layers "F.Cu" "B.Cu" "In1.Cu" "In2.Cu" "In3.Cu" "In4.Cu" "In5.Cu" "In6.Cu"
				"In7.Cu" "In8.Cu" "In9.Cu" "In10.Cu"
			)
			(hatch none 0.5)
			(connect_pads
				(clearance 0)
			)
			(min_thickness 0.25)
			(keepout
				(tracks not_allowed)
				(vias allowed)
				(pads allowed)
				(copperpour not_allowed)
				(footprints allowed)
			)
			(placement
				(enabled no)
				(sheetname "")
			)
			(fill
				(thermal_gap 0.5)
				(thermal_bridge_width 0.5)
				(island_removal_mode 0)
			)
			(polygon
				(pts
					(arc
						(start 103.48722 26.378662)
						(mid 101.63302 26.378662)
						(end 103.48722 26.378662)
					)
				)
			)
		)
		(zone
			(layers "F.Cu" "B.Cu" "In1.Cu" "In2.Cu" "In3.Cu" "In4.Cu" "In5.Cu" "In6.Cu"
				"In7.Cu" "In8.Cu" "In9.Cu" "In10.Cu"
			)
			(hatch none 0.5)
			(connect_pads
				(clearance 0)
			)
			(min_thickness 0.25)
			(keepout
				(tracks not_allowed)
				(vias allowed)
				(pads allowed)
				(copperpour not_allowed)
				(footprints allowed)
			)
			(placement
				(enabled no)
				(sheetname "")
			)
			(fill
				(thermal_gap 0.5)
				(thermal_bridge_width 0.5)
				(island_removal_mode 0)
			)
			(polygon
				(pts
					(arc
						(start 103.48722 32.728662)
						(mid 101.63302 32.728662)
						(end 103.48722 32.728662)
					)
				)
			)
		)
		(zone
			(layer "B.Cu")
			(hatch none 0.5)
			(connect_pads
				(clearance 0)
			)
			(min_thickness 0.25)
			(keepout
				(tracks not_allowed)
				(vias allowed)
				(pads allowed)
				(copperpour not_allowed)
				(footprints allowed)
			)
			(placement
				(enabled no)
				(sheetname "")
			)
			(fill
				(thermal_gap 0.5)
				(thermal_bridge_width 0.5)
				(island_removal_mode 0)
			)
			(polygon
				(pts
					(xy 100.74148 30.379162) (xy 100.836984 30.379162) (xy 100.836984 29.782262) (xy 101.243384 29.782262)
					(xy 101.243384 30.379162) (xy 101.336856 30.379162) (xy 101.336856 29.782262) (xy 101.743256 29.782262)
					(xy 101.743256 30.379162) (xy 101.83876 30.379162) (xy 101.83876 29.680662) (xy 100.74148 29.680662)
				)
			)
		)
	)
)
